(kicad_pcb
	(version 20260206)
	(generator "pcbnew")
	(generator_version "10.0")
	(general
		(thickness 1.6)
		(legacy_teardrops no)
	)
	(paper "A4")
	(title_block
		(title "v1-chassis-manager — T6M_CM_d_v01_1031_1645.brd")
		(comment 1 "Open CloudServer (Microsoft) / footprints 1523-1532 of 2512")
	)
	(layers
		(0 "F.Cu" signal "TOP")
		(4 "In1.Cu" signal "GND1")
		(6 "In2.Cu" signal "IN1")
		(8 "In3.Cu" signal "VCC1")
		(10 "In4.Cu" signal "VCC2")
		(12 "In5.Cu" signal "GND2")
		(14 "In6.Cu" signal "IN2")
		(16 "In7.Cu" signal "IN3")
		(18 "In8.Cu" signal "GND3")
		(2 "B.Cu" signal "BOTTOM")
		(9 "F.Adhes" user "F.Adhesive")
		(11 "B.Adhes" user "B.Adhesive")
		(13 "F.Paste" user "Package Geometry/Pastemask Top")
		(15 "B.Paste" user "Package Geometry/Pastemask Bottom")
		(5 "F.SilkS" user "Ref Des/Silkscreen Top")
		(7 "B.SilkS" user "Ref Des/Silkscreen Bottom")
		(1 "F.Mask" user "Board Geometry/Soldermask Top")
		(3 "B.Mask" user "Board Geometry/Soldermask Bottom")
		(17 "Dwgs.User" user "User.Drawings")
		(19 "Cmts.User" user "User.Comments")
		(21 "Eco1.User" user "User.Eco1")
		(23 "Eco2.User" user "User.Eco2")
		(25 "Edge.Cuts" user "Board Geometry/Outline")
		(27 "Margin" user)
		(31 "F.CrtYd" user "Package Geometry/Place Bound Top")
		(29 "B.CrtYd" user "Package Geometry/Place Bound Bottom")
		(35 "F.Fab" user "Ref Des/Assembly Top")
		(33 "B.Fab" user "Ref Des/Assembly Bottom")
	)
	(footprint ""
		(layer "F.Cu")
		(at 126.82728 -114.239294)
		(property "Reference" "R8"
			(at -0.625348 -2.0955 0)
			(unlocked yes)
			(layer "F.SilkS")
			(effects
				(font
					(size 0.7874 0.5842)
					(thickness 0.1524)
				)
				(justify left)
			)
		)
		(property "Value" ""
			(at 0 0 0)
			(layer "F.Fab")
			(effects
				(font
					(size 1.27 1.27)
				)
			)
		)
		(duplicate_pad_numbers_are_jumpers no)
		(fp_line
			(start -0.7874 -0.4064)
			(end 0.7874 -0.4064)
			(stroke
				(width 0.1524)
				(type default)
			)
			(layer "F.SilkS")
		)
		(fp_line
			(start -0.7874 0.4064)
			(end -0.7874 -0.4064)
			(stroke
				(width 0.1524)
				(type default)
			)
			(layer "F.SilkS")
		)
		(fp_line
			(start 0.7874 -0.4064)
			(end 0.7874 0.4064)
			(stroke
				(width 0.1524)
				(type default)
			)
			(layer "F.SilkS")
		)
		(fp_line
			(start 0.7874 0.4064)
			(end -0.7874 0.4064)
			(stroke
				(width 0.1524)
				(type default)
			)
			(layer "F.SilkS")
		)
		(fp_poly
			(pts
				(xy -0.508 0.2794) (xy -0.508 0.2286) (xy -0.635 0.2286) (xy -0.635 -0.254) (xy -0.5334 -0.254)
				(xy -0.5334 -0.2794) (xy 0.5334 -0.2794) (xy 0.5334 -0.254) (xy 0.635 -0.254) (xy 0.635 0.254) (xy 0.5334 0.254)
				(xy 0.5334 0.2794)
			)
			(stroke
				(width 0)
				(type default)
			)
			(fill no)
			(layer "F.CrtYd")
		)
		(pad "1" smd rect
			(at 0.40005 0)
			(size 0.4572 0.508)
			(layers "F.Cu" "F.Mask" "F.Paste")
			(net "FM_CPLD_CLK_R_PG_NODE1_R")
		)
		(pad "2" smd rect
			(at -0.40005 0)
			(size 0.4572 0.508)
			(layers "F.Cu" "F.Mask" "F.Paste")
			(net "P3V3_CLK_NODE1")
		)
	)
	(footprint ""
		(layer "F.Cu")
		(at 153.572972 -26.601928 180)
		(property "Reference" "C533"
			(at -5.442712 -0.855218 90)
			(unlocked yes)
			(layer "F.SilkS")
			(effects
				(font
					(size 0.7874 0.5842)
					(thickness 0.1524)
				)
				(justify left)
			)
		)
		(property "Value" ""
			(at 0 0 180)
			(layer "F.Fab")
			(effects
				(font
					(size 1.27 1.27)
				)
			)
		)
		(duplicate_pad_numbers_are_jumpers no)
		(fp_line
			(start 0.7874 0.4064)
			(end -0.7874 0.4064)
			(stroke
				(width 0.1524)
				(type default)
			)
			(layer "F.SilkS")
		)
		(fp_line
			(start 0.7874 -0.4064)
			(end 0.7874 0.4064)
			(stroke
				(width 0.1524)
				(type default)
			)
			(layer "F.SilkS")
		)
		(fp_line
			(start 0 0.381)
			(end 0 -0.381)
			(stroke
				(width 0.1524)
				(type default)
			)
			(layer "F.SilkS")
		)
		(fp_line
			(start -0.7874 0.4064)
			(end -0.7874 -0.4064)
			(stroke
				(width 0.1524)
				(type default)
			)
			(layer "F.SilkS")
		)
		(fp_line
			(start -0.7874 -0.4064)
			(end 0.7874 -0.4064)
			(stroke
				(width 0.1524)
				(type default)
			)
			(layer "F.SilkS")
		)
		(fp_poly
			(pts
				(xy -0.5334 0.254) (xy -0.635 0.254) (xy -0.635 0.2286) (xy -0.635 -0.254) (xy -0.5334 -0.254) (xy -0.5334 -0.2794)
				(xy 0.5334 -0.2794) (xy 0.5334 -0.254) (xy 0.635 -0.254) (xy 0.635 0.254) (xy 0.5334 0.254) (xy 0.5334 0.2794)
				(xy -0.508 0.2794) (xy -0.5334 0.2794)
			)
			(stroke
				(width 0)
				(type default)
			)
			(fill no)
			(layer "F.CrtYd")
		)
		(pad "1" smd rect
			(at 0.40005 0 180)
			(size 0.4572 0.508)
			(layers "F.Cu" "F.Mask" "F.Paste")
			(net "N21624848")
		)
		(pad "2" smd rect
			(at -0.40005 0 180)
			(size 0.4572 0.508)
			(layers "F.Cu" "F.Mask" "F.Paste")
			(net "N21624850")
		)
	)
	(footprint ""
		(layer "F.Cu")
		(at 176.58842 -48.354742 90)
		(property "Reference" "FS4"
			(at -0.050292 1.750568 90)
			(unlocked yes)
			(layer "F.SilkS")
			(effects
				(font
					(size 0.7874 0.5842)
					(thickness 0.1524)
				)
				(justify left)
			)
		)
		(property "Value" ""
			(at 0 0 90)
			(layer "F.Fab")
			(effects
				(font
					(size 1.27 1.27)
				)
			)
		)
		(duplicate_pad_numbers_are_jumpers no)
		(fp_line
			(start 3.550412 -1.050036)
			(end 3.550412 1.050036)
			(stroke
				(width 0.1524)
				(type default)
			)
			(layer "F.SilkS")
		)
		(fp_line
			(start -0.650494 -1.050036)
			(end 3.550412 -1.050036)
			(stroke
				(width 0.1524)
				(type default)
			)
			(layer "F.SilkS")
		)
		(fp_line
			(start 3.550412 1.050036)
			(end -0.650494 1.050036)
			(stroke
				(width 0.1524)
				(type default)
			)
			(layer "F.SilkS")
		)
		(fp_line
			(start -0.650494 1.050036)
			(end -0.650494 -1.050036)
			(stroke
				(width 0.1524)
				(type default)
			)
			(layer "F.SilkS")
		)
		(fp_poly
			(pts
				(xy 3.228086 -0.9652) (xy 3.228086 -1.100074) (xy -0.327914 -1.100074) (xy -0.327914 -0.9652) (xy -0.556514 -0.9652)
				(xy -0.556514 0.9652) (xy -0.327914 0.9652) (xy -0.327914 1.100074) (xy 3.228086 1.100074) (xy 3.228086 0.9652)
				(xy 3.456686 0.9652) (xy 3.456686 -0.9652)
			)
			(stroke
				(width 0)
				(type default)
			)
			(fill no)
			(layer "F.CrtYd")
		)
		(fp_text user "1"
			(at -1.18491 -1.651 0)
			(unlocked yes)
			(layer "F.SilkS")
			(effects
				(font
					(size 0.635 0.4064)
					(thickness 0.1524)
				)
				(justify left)
			)
		)
		(fp_text user "2"
			(at 3.151632 1.41351 0)
			(unlocked yes)
			(layer "F.SilkS")
			(effects
				(font
					(size 0.635 0.4064)
					(thickness 0.1524)
				)
				(justify left)
			)
		)
		(pad "1" smd rect
			(at 0 0 90)
			(size 1.016 1.8034)
			(layers "F.Cu" "F.Mask" "F.Paste")
			(net "P5V_NODE1")
		)
		(pad "2" smd rect
			(at 2.899918 0 90)
			(size 1.016 1.8034)
			(layers "F.Cu" "F.Mask" "F.Paste")
			(net "USBPWR_P1")
		)
	)
	(footprint ""
		(layer "F.Cu")
		(at 74.353166 -96.709992 -90)
		(property "Reference" "R105"
			(at 54.98719 -28.313888 90)
			(unlocked yes)
			(layer "F.SilkS")
			(effects
				(font
					(size 0.7874 0.5842)
					(thickness 0.1524)
				)
				(justify left)
			)
		)
		(property "Value" ""
			(at 0 0 270)
			(layer "F.Fab")
			(effects
				(font
					(size 1.27 1.27)
				)
			)
		)
		(duplicate_pad_numbers_are_jumpers no)
		(fp_line
			(start -0.7874 0.4064)
			(end -0.7874 -0.4064)
			(stroke
				(width 0.1524)
				(type default)
			)
			(layer "F.SilkS")
		)
		(fp_line
			(start 0.7874 0.4064)
			(end -0.7874 0.4064)
			(stroke
				(width 0.1524)
				(type default)
			)
			(layer "F.SilkS")
		)
		(fp_line
			(start -0.7874 -0.4064)
			(end 0.7874 -0.4064)
			(stroke
				(width 0.1524)
				(type default)
			)
			(layer "F.SilkS")
		)
		(fp_line
			(start 0.7874 -0.4064)
			(end 0.7874 0.4064)
			(stroke
				(width 0.1524)
				(type default)
			)
			(layer "F.SilkS")
		)
		(fp_poly
			(pts
				(xy -0.508 0.2794) (xy -0.508 0.2286) (xy -0.635 0.2286) (xy -0.635 -0.254) (xy -0.5334 -0.254)
				(xy -0.5334 -0.2794) (xy 0.5334 -0.2794) (xy 0.5334 -0.254) (xy 0.635 -0.254) (xy 0.635 0.254) (xy 0.5334 0.254)
				(xy 0.5334 0.2794)
			)
			(stroke
				(width 0)
				(type default)
			)
			(fill no)
			(layer "F.CrtYd")
		)
		(pad "1" smd rect
			(at 0.40005 0 270)
			(size 0.4572 0.508)
			(layers "F.Cu" "F.Mask" "F.Paste")
			(net "H_CPU_NODE1_ERR2_R")
		)
		(pad "2" smd rect
			(at -0.40005 0 270)
			(size 0.4572 0.508)
			(layers "F.Cu" "F.Mask" "F.Paste")
			(net "P3V3_NODE1")
		)
	)
	(footprint ""
		(layer "F.Cu")
		(at 21.928582 -56.828436 90)
		(property "Reference" "U44"
			(at -2.449068 13.606018 0)
			(unlocked yes)
			(layer "F.SilkS")
			(effects
				(font
					(size 0.7874 0.5842)
					(thickness 0.1524)
				)
			)
		)
		(property "Value" ""
			(at 0 0 90)
			(layer "F.Fab")
			(effects
				(font
					(size 1.27 1.27)
				)
			)
		)
		(duplicate_pad_numbers_are_jumpers no)
		(fp_line
			(start 1.651 -1.905)
			(end 1.651 1.905)
			(stroke
				(width 0.1524)
				(type default)
			)
			(layer "F.SilkS")
		)
		(fp_line
			(start -1.651 -1.905)
			(end 1.651 -1.905)
			(stroke
				(width 0.1524)
				(type default)
			)
			(layer "F.SilkS")
		)
		(fp_line
			(start 1.651 1.905)
			(end -1.651 1.905)
			(stroke
				(width 0.1524)
				(type default)
			)
			(layer "F.SilkS")
		)
		(fp_line
			(start -1.651 1.905)
			(end -1.651 -1.905)
			(stroke
				(width 0.1524)
				(type default)
			)
			(layer "F.SilkS")
		)
		(fp_poly
			(pts
				(xy -1.524 0.7112) (xy -1.524 1.7526) (xy -0.508 1.7526) (xy -0.508 0.6985) (xy 0.508 0.6985) (xy 0.508 1.7526)
				(xy 1.524 1.7526) (xy 1.524 0.6985) (xy 1.524 -0.6985) (xy 0.508 -0.6985) (xy 0.508 -1.7526) (xy -0.508 -1.7526)
				(xy -0.508 -0.6985) (xy -1.524 -0.6985) (xy -1.524 0.6985)
			)
			(stroke
				(width 0)
				(type default)
			)
			(fill no)
			(layer "F.CrtYd")
		)
		(fp_text user "3"
			(at -0.429514 -2.62509 0)
			(unlocked yes)
			(layer "F.SilkS")
			(effects
				(font
					(size 0.635 0.4064)
					(thickness 0.1524)
				)
			)
		)
		(fp_text user "2"
			(at 2.237486 1.81991 0)
			(unlocked yes)
			(layer "F.SilkS")
			(effects
				(font
					(size 0.635 0.4064)
					(thickness 0.1524)
				)
			)
		)
		(fp_text user "1"
			(at -0.683514 2.07391 0)
			(unlocked yes)
			(layer "F.SilkS")
			(effects
				(font
					(size 0.635 0.4064)
					(thickness 0.1524)
				)
			)
		)
		(pad "1" smd rect
			(at -1.016 1.1176 90)
			(size 1.016 1.27)
			(layers "F.Cu" "F.Mask" "F.Paste")
			(net "GND")
		)
		(pad "2" smd rect
			(at 1.016 1.1176 90)
			(size 1.016 1.27)
			(layers "F.Cu" "F.Mask" "F.Paste")
			(net "P5V_CRT")
		)
		(pad "3" smd rect
			(at 0 -1.1176 90)
			(size 1.016 1.27)
			(layers "F.Cu" "F.Mask" "F.Paste")
			(net "CRT_B")
		)
	)
	(footprint ""
		(layer "F.Cu")
		(at 182.45709 -149.212554 -90)
		(property "Reference" "R595"
			(at 1.75641 2.137918 90)
			(unlocked yes)
			(layer "F.SilkS")
			(effects
				(font
					(size 0.7874 0.5842)
					(thickness 0.1524)
				)
				(justify left)
			)
		)
		(property "Value" ""
			(at 0 0 270)
			(layer "F.Fab")
			(effects
				(font
					(size 1.27 1.27)
				)
			)
		)
		(duplicate_pad_numbers_are_jumpers no)
		(fp_line
			(start -2.2098 0.9398)
			(end -2.2098 -0.9398)
			(stroke
				(width 0.1524)
				(type default)
			)
			(layer "F.SilkS")
		)
		(fp_line
			(start 2.2098 0.9398)
			(end -2.2098 0.9398)
			(stroke
				(width 0.1524)
				(type default)
			)
			(layer "F.SilkS")
		)
		(fp_line
			(start -2.2098 -0.9398)
			(end 2.2098 -0.9398)
			(stroke
				(width 0.1524)
				(type default)
			)
			(layer "F.SilkS")
		)
		(fp_line
			(start 2.2098 -0.9398)
			(end 2.2098 0.9398)
			(stroke
				(width 0.1524)
				(type default)
			)
			(layer "F.SilkS")
		)
		(fp_poly
			(pts
				(xy 2.0574 0.8382) (xy 2.0574 -0.8382) (xy 2.0574 -0.9398) (xy -2.0574 -0.9398) (xy -2.0574 -0.8382)
				(xy -2.0574 0.8382) (xy -2.0574 0.9398) (xy 2.0574 0.9398)
			)
			(stroke
				(width 0)
				(type default)
			)
			(fill no)
			(layer "F.CrtYd")
		)
		(pad "1" smd rect
			(at 1.4732 0 270)
			(size 1.1684 1.5748)
			(layers "F.Cu" "F.Mask" "F.Paste")
			(net "LAN2_CTRL_P1V9")
		)
		(pad "2" smd rect
			(at -1.4732 0 270)
			(size 1.1684 1.5748)
			(layers "F.Cu" "F.Mask" "F.Paste")
			(net "LAN2_CTRL_P1V9_R")
		)
	)
	(footprint ""
		(layer "F.Cu")
		(at 162.035998 -142.04823 180)
		(property "Reference" "Y5"
			(at -0.320294 -2.38252 0)
			(unlocked yes)
			(layer "F.SilkS")
			(effects
				(font
					(size 0.7874 0.5842)
					(thickness 0.1524)
				)
				(justify left)
			)
		)
		(property "Value" ""
			(at 0 0 180)
			(layer "F.Fab")
			(effects
				(font
					(size 1.27 1.27)
				)
			)
		)
		(duplicate_pad_numbers_are_jumpers no)
		(fp_line
			(start 3.3528 1.700022)
			(end -3.3528 1.700022)
			(stroke
				(width 0.1524)
				(type default)
			)
			(layer "F.SilkS")
		)
		(fp_line
			(start 3.3528 -1.700022)
			(end 3.3528 1.700022)
			(stroke
				(width 0.1524)
				(type default)
			)
			(layer "F.SilkS")
		)
		(fp_line
			(start -3.3528 1.700022)
			(end -3.3528 -1.700022)
			(stroke
				(width 0.1524)
				(type default)
			)
			(layer "F.SilkS")
		)
		(fp_line
			(start -3.3528 -1.700022)
			(end 3.3528 -1.700022)
			(stroke
				(width 0.1524)
				(type default)
			)
			(layer "F.SilkS")
		)
		(fp_poly
			(pts
				(xy -2.599944 1.700022) (xy 2.599944 1.700022) (xy 2.599944 1.1176) (xy 3.2258 1.1176) (xy 3.2258 -1.1176)
				(xy 2.599944 -1.1176) (xy 2.599944 -1.700022) (xy -2.599944 -1.700022) (xy -2.599944 -1.1176) (xy -3.2258 -1.1176)
				(xy -3.2258 1.1176) (xy -2.599944 1.1176)
			)
			(stroke
				(width 0)
				(type default)
			)
			(fill no)
			(layer "F.CrtYd")
		)
		(fp_line
			(start 2.599944 1.700022)
			(end -2.599944 1.700022)
			(stroke
				(width 0.1)
				(type default)
			)
			(layer "F.Fab")
		)
		(fp_line
			(start 2.599944 -1.700022)
			(end 2.599944 1.700022)
			(stroke
				(width 0.1)
				(type default)
			)
			(layer "F.Fab")
		)
		(fp_line
			(start -2.599944 1.700022)
			(end -2.599944 -1.700022)
			(stroke
				(width 0.1)
				(type default)
			)
			(layer "F.Fab")
		)
		(fp_line
			(start -2.599944 -1.700022)
			(end 2.599944 -1.700022)
			(stroke
				(width 0.1)
				(type default)
			)
			(layer "F.Fab")
		)
		(pad "1" smd rect
			(at -2.100072 0 180)
			(size 2.2098 2.2098)
			(layers "F.Cu" "F.Mask" "F.Paste")
			(net "LAN2_XTAL_IN")
		)
		(pad "2" smd rect
			(at 2.100072 0 180)
			(size 2.2098 2.2098)
			(layers "F.Cu" "F.Mask" "F.Paste")
			(net "LAN2_XTAL_OUT")
		)
	)
	(footprint ""
		(layer "F.Cu")
		(at 127.568452 -153.67635 90)
		(property "Reference" "R296"
			(at -111.020352 -58.8264 90)
			(unlocked yes)
			(layer "F.SilkS")
			(effects
				(font
					(size 0.7874 0.5842)
					(thickness 0.1524)
				)
				(justify left)
			)
		)
		(property "Value" ""
			(at 0 0 90)
			(layer "F.Fab")
			(effects
				(font
					(size 1.27 1.27)
				)
			)
		)
		(duplicate_pad_numbers_are_jumpers no)
		(fp_line
			(start 0.7874 -0.4064)
			(end 0.7874 0.4064)
			(stroke
				(width 0.1524)
				(type default)
			)
			(layer "F.SilkS")
		)
		(fp_line
			(start -0.7874 -0.4064)
			(end 0.7874 -0.4064)
			(stroke
				(width 0.1524)
				(type default)
			)
			(layer "F.SilkS")
		)
		(fp_line
			(start 0.7874 0.4064)
			(end -0.7874 0.4064)
			(stroke
				(width 0.1524)
				(type default)
			)
			(layer "F.SilkS")
		)
		(fp_line
			(start -0.7874 0.4064)
			(end -0.7874 -0.4064)
			(stroke
				(width 0.1524)
				(type default)
			)
			(layer "F.SilkS")
		)
		(fp_poly
			(pts
				(xy -0.508 0.2794) (xy -0.508 0.2286) (xy -0.635 0.2286) (xy -0.635 -0.254) (xy -0.5334 -0.254)
				(xy -0.5334 -0.2794) (xy 0.5334 -0.2794) (xy 0.5334 -0.254) (xy 0.635 -0.254) (xy 0.635 0.254) (xy 0.5334 0.254)
				(xy 0.5334 0.2794)
			)
			(stroke
				(width 0)
				(type default)
			)
			(fill no)
			(layer "F.CrtYd")
		)
		(pad "1" smd rect
			(at 0.40005 0 90)
			(size 0.4572 0.508)
			(layers "F.Cu" "F.Mask" "F.Paste")
			(net "GND")
		)
		(pad "2" smd rect
			(at -0.40005 0 90)
			(size 0.4572 0.508)
			(layers "F.Cu" "F.Mask" "F.Paste")
			(net "PCIE_SW_TMS")
		)
	)
	(footprint ""
		(layer "F.Cu")
		(at 111.699548 -131.998974 90)
		(property "Reference" "PR42"
			(at -0.694944 5.295646 90)
			(unlocked yes)
			(layer "F.SilkS")
			(effects
				(font
					(size 0.7874 0.5842)
					(thickness 0.1524)
				)
				(justify left)
			)
		)
		(property "Value" ""
			(at 0 0 90)
			(layer "F.Fab")
			(effects
				(font
					(size 1.27 1.27)
				)
			)
		)
		(duplicate_pad_numbers_are_jumpers no)
		(fp_line
			(start 0.7874 -0.4064)
			(end 0.7874 0.4064)
			(stroke
				(width 0.1524)
				(type default)
			)
			(layer "F.SilkS")
		)
		(fp_line
			(start -0.7874 -0.4064)
			(end 0.7874 -0.4064)
			(stroke
				(width 0.1524)
				(type default)
			)
			(layer "F.SilkS")
		)
		(fp_line
			(start 0.7874 0.4064)
			(end -0.7874 0.4064)
			(stroke
				(width 0.1524)
				(type default)
			)
			(layer "F.SilkS")
		)
		(fp_line
			(start -0.7874 0.4064)
			(end -0.7874 -0.4064)
			(stroke
				(width 0.1524)
				(type default)
			)
			(layer "F.SilkS")
		)
		(fp_poly
			(pts
				(xy -0.508 0.2794) (xy -0.508 0.2286) (xy -0.635 0.2286) (xy -0.635 -0.254) (xy -0.5334 -0.254)
				(xy -0.5334 -0.2794) (xy 0.5334 -0.2794) (xy 0.5334 -0.254) (xy 0.635 -0.254) (xy 0.635 0.254) (xy 0.5334 0.254)
				(xy 0.5334 0.2794)
			)
			(stroke
				(width 0)
				(type default)
			)
			(fill no)
			(layer "F.CrtYd")
		)
		(pad "1" smd rect
			(at 0.40005 0 90)
			(size 0.4572 0.508)
			(layers "F.Cu" "F.Mask" "F.Paste")
			(net "VR_PVCCP_NODE1_TONSET")
		)
		(pad "2" smd rect
			(at -0.40005 0 90)
			(size 0.4572 0.508)
			(layers "F.Cu" "F.Mask" "F.Paste")
			(net "VR_PVCCP_NODE1_TONSET_R")
		)
	)
	(footprint ""
		(layer "F.Cu")
		(at 148.937726 -150.264368 90)
		(property "Reference" "R1227"
			(at -2.863596 1.071118 90)
			(unlocked yes)
			(layer "F.SilkS")
			(effects
				(font
					(size 0.7874 0.5842)
					(thickness 0.1524)
				)
				(justify left)
			)
		)
		(property "Value" ""
			(at 0 0 90)
			(layer "F.Fab")
			(effects
				(font
					(size 1.27 1.27)
				)
			)
		)
		(duplicate_pad_numbers_are_jumpers no)
		(fp_line
			(start 0.7874 -0.4064)
			(end 0.7874 0.4064)
			(stroke
				(width 0.1524)
				(type default)
			)
			(layer "F.SilkS")
		)
		(fp_line
			(start -0.7874 -0.4064)
			(end 0.7874 -0.4064)
			(stroke
				(width 0.1524)
				(type default)
			)
			(layer "F.SilkS")
		)
		(fp_line
			(start 0.7874 0.4064)
			(end -0.7874 0.4064)
			(stroke
				(width 0.1524)
				(type default)
			)
			(layer "F.SilkS")
		)
		(fp_line
			(start -0.7874 0.4064)
			(end -0.7874 -0.4064)
			(stroke
				(width 0.1524)
				(type default)
			)
			(layer "F.SilkS")
		)
		(fp_poly
			(pts
				(xy -0.508 0.2794) (xy -0.508 0.2286) (xy -0.635 0.2286) (xy -0.635 -0.254) (xy -0.5334 -0.254)
				(xy -0.5334 -0.2794) (xy 0.5334 -0.2794) (xy 0.5334 -0.254) (xy 0.635 -0.254) (xy 0.635 0.254) (xy 0.5334 0.254)
				(xy 0.5334 0.2794)
			)
			(stroke
				(width 0)
				(type default)
			)
			(fill no)
			(layer "F.CrtYd")
		)
		(pad "1" smd rect
			(at 0.40005 0 90)
			(size 0.4572 0.508)
			(layers "F.Cu" "F.Mask" "F.Paste")
			(net "PCIE_SW_WP_N")
		)
		(pad "2" smd rect
			(at -0.40005 0 90)
			(size 0.4572 0.508)
			(layers "F.Cu" "F.Mask" "F.Paste")
			(net "GND")
		)
	)
)
